(kicad_pcb
	(version 20260206)
	(generator "pcbnew")
	(generator_version "10.0")
	(general
		(thickness 1.6)
		(legacy_teardrops no)
	)
	(paper "A4")
	(title_block
		(title "03242023_DA0F0TMBIJ0_F0T_Motherboard_J_brd_V01_OCP.brd")
		(comment 1 "Grand Teton / footprints 5856-5863 of 6105")
	)
	(layers
		(0 "F.Cu" signal "TOP")
		(4 "In1.Cu" signal "GND")
		(6 "In2.Cu" signal "IN1")
		(8 "In3.Cu" signal "GND1")
		(10 "In4.Cu" signal "IN2")
		(12 "In5.Cu" signal "GND2")
		(14 "In6.Cu" signal "IN3")
		(16 "In7.Cu" signal "GND3")
		(18 "In8.Cu" signal "VCC")
		(20 "In9.Cu" signal "VCC1")
		(22 "In10.Cu" signal "GND4")
		(24 "In11.Cu" signal "IN4")
		(26 "In12.Cu" signal "GND5")
		(28 "In13.Cu" signal "IN5")
		(30 "In14.Cu" signal "GND6")
		(32 "In15.Cu" signal "IN6")
		(34 "In16.Cu" signal "GND7")
		(2 "B.Cu" signal "BOTTOM")
		(9 "F.Adhes" user "F.Adhesive")
		(11 "B.Adhes" user "B.Adhesive")
		(13 "F.Paste" user "Package Geometry/Pastemask Top")
		(15 "B.Paste" user "Package Geometry/Pastemask Bottom")
		(5 "F.SilkS" user "Ref Des/Silkscreen Top")
		(7 "B.SilkS" user "Ref Des/Silkscreen Bottom")
		(1 "F.Mask" user "Board Geometry/Soldermask Top")
		(3 "B.Mask" user "Board Geometry/Soldermask Bottom")
		(17 "Dwgs.User" user "User.Drawings")
		(19 "Cmts.User" user "User.Comments")
		(21 "Eco1.User" user "User.Eco1")
		(23 "Eco2.User" user "User.Eco2")
		(25 "Edge.Cuts" user "Board Geometry/Outline")
		(27 "Margin" user)
		(31 "F.CrtYd" user "Package Geometry/Place Bound Top")
		(29 "B.CrtYd" user "Package Geometry/Place Bound Bottom")
		(35 "F.Fab" user "Ref Des/Assembly Top")
		(33 "B.Fab" user "Ref Des/Assembly Bottom")
	)
	(footprint ""
		(layer "B.Cu")
		(at 105.670604 -294.01008)
		(property "Reference" "C325"
			(at 0 0 0)
			(layer "B.SilkS")
			(hide yes)
			(effects
				(font
					(size 1.27 1.27)
				)
				(justify mirror)
			)
		)
		(property "Value" ""
			(at 0 0 0)
			(layer "B.Fab")
			(effects
				(font
					(size 1.27 1.27)
				)
				(justify mirror)
			)
		)
		(duplicate_pad_numbers_are_jumpers no)
		(fp_line
			(start -1.524 -0.762)
			(end -1.524 0.762)
			(stroke
				(width 0.1524)
				(type default)
			)
			(layer "B.SilkS")
		)
		(fp_line
			(start -1.524 0.762)
			(end 1.524 0.762)
			(stroke
				(width 0.1524)
				(type default)
			)
			(layer "B.SilkS")
		)
		(fp_line
			(start 1.524 -0.762)
			(end -1.524 -0.762)
			(stroke
				(width 0.1524)
				(type default)
			)
			(layer "B.SilkS")
		)
		(fp_line
			(start 1.524 0.762)
			(end 1.524 -0.762)
			(stroke
				(width 0.1524)
				(type default)
			)
			(layer "B.SilkS")
		)
		(fp_line
			(start -1.1049 -0.724916)
			(end 1.1049 -0.724916)
			(stroke
				(width 0.1)
				(type default)
			)
			(layer "B.Fab")
		)
		(fp_line
			(start -1.1049 0.724916)
			(end -1.1049 -0.724916)
			(stroke
				(width 0.1)
				(type default)
			)
			(layer "B.Fab")
		)
		(fp_line
			(start 1.1049 -0.724916)
			(end 1.1049 0.724916)
			(stroke
				(width 0.1)
				(type default)
			)
			(layer "B.Fab")
		)
		(fp_line
			(start 1.1049 0.724916)
			(end -1.1049 0.724916)
			(stroke
				(width 0.1)
				(type default)
			)
			(layer "B.Fab")
		)
		(pad "1" smd rect
			(at 0.889 0)
			(size 1.016 1.27)
			(layers "B.Cu" "B.Mask" "B.Paste")
			(net "PVCCIN_CPU1")
		)
		(pad "2" smd rect
			(at -0.889 0)
			(size 1.016 1.27)
			(layers "B.Cu" "B.Mask" "B.Paste")
			(net "GND")
		)
	)
	(footprint ""
		(layer "B.Cu")
		(at 452.028814 -321.549776 -90)
		(property "Reference" "C49"
			(at 0 0 90)
			(layer "B.SilkS")
			(hide yes)
			(effects
				(font
					(size 1.27 1.27)
				)
				(justify mirror)
			)
		)
		(property "Value" ""
			(at 0 0 90)
			(layer "B.Fab")
			(effects
				(font
					(size 1.27 1.27)
				)
				(justify mirror)
			)
		)
		(duplicate_pad_numbers_are_jumpers no)
		(fp_line
			(start -1.524 0.762)
			(end 1.524 0.762)
			(stroke
				(width 0.1524)
				(type default)
			)
			(layer "B.SilkS")
		)
		(fp_line
			(start 1.524 0.762)
			(end 1.524 -0.762)
			(stroke
				(width 0.1524)
				(type default)
			)
			(layer "B.SilkS")
		)
		(fp_line
			(start -1.524 -0.762)
			(end -1.524 0.762)
			(stroke
				(width 0.1524)
				(type default)
			)
			(layer "B.SilkS")
		)
		(fp_line
			(start 1.524 -0.762)
			(end -1.524 -0.762)
			(stroke
				(width 0.1524)
				(type default)
			)
			(layer "B.SilkS")
		)
		(fp_line
			(start -1.1049 0.724916)
			(end -1.1049 -0.724916)
			(stroke
				(width 0.1)
				(type default)
			)
			(layer "B.Fab")
		)
		(fp_line
			(start 1.1049 0.724916)
			(end -1.1049 0.724916)
			(stroke
				(width 0.1)
				(type default)
			)
			(layer "B.Fab")
		)
		(fp_line
			(start -1.1049 -0.724916)
			(end 1.1049 -0.724916)
			(stroke
				(width 0.1)
				(type default)
			)
			(layer "B.Fab")
		)
		(fp_line
			(start 1.1049 -0.724916)
			(end 1.1049 0.724916)
			(stroke
				(width 0.1)
				(type default)
			)
			(layer "B.Fab")
		)
		(pad "1" smd rect
			(at 0.889 0 270)
			(size 1.016 1.27)
			(layers "B.Cu" "B.Mask" "B.Paste")
			(net "P12V_S3_AUX_CPU0_NVDIMM")
		)
		(pad "2" smd rect
			(at -0.889 0 270)
			(size 1.016 1.27)
			(layers "B.Cu" "B.Mask" "B.Paste")
			(net "GND")
		)
	)
	(footprint ""
		(layer "B.Cu")
		(at 340.35746 -66.425064 90)
		(property "Reference" "C167"
			(at 0 0 90)
			(layer "B.SilkS")
			(hide yes)
			(effects
				(font
					(size 1.27 1.27)
				)
				(justify mirror)
			)
		)
		(property "Value" ""
			(at 0 0 90)
			(layer "B.Fab")
			(effects
				(font
					(size 1.27 1.27)
				)
				(justify mirror)
			)
		)
		(duplicate_pad_numbers_are_jumpers no)
		(fp_line
			(start 0.299974 -0.150114)
			(end -0.299974 -0.150114)
			(stroke
				(width 0.1)
				(type default)
			)
			(layer "B.Fab")
		)
		(fp_line
			(start -0.299974 -0.150114)
			(end -0.299974 0.150114)
			(stroke
				(width 0.1)
				(type default)
			)
			(layer "B.Fab")
		)
		(fp_line
			(start 0.299974 0.150114)
			(end 0.299974 -0.150114)
			(stroke
				(width 0.1)
				(type default)
			)
			(layer "B.Fab")
		)
		(fp_line
			(start -0.299974 0.150114)
			(end 0.299974 0.150114)
			(stroke
				(width 0.1)
				(type default)
			)
			(layer "B.Fab")
		)
		(pad "1" smd rect
			(at 0.2667 0 270)
			(size 0.3048 0.381)
			(layers "B.Cu" "B.Mask" "B.Paste")
			(net "DMI_CPU0_PCH_RX_C_DN<1>")
		)
		(pad "2" smd rect
			(at -0.2667 0 270)
			(size 0.3048 0.381)
			(layers "B.Cu" "B.Mask" "B.Paste")
			(net "DMI_CPU0_PCH_RX_DN<1>")
		)
	)
	(footprint ""
		(layer "B.Cu")
		(at 171.985178 -346.586302 -90)
		(property "Reference" "PC418"
			(at 0 0 90)
			(layer "B.SilkS")
			(hide yes)
			(effects
				(font
					(size 1.27 1.27)
				)
				(justify mirror)
			)
		)
		(property "Value" ""
			(at 0 0 90)
			(layer "B.Fab")
			(effects
				(font
					(size 1.27 1.27)
				)
				(justify mirror)
			)
		)
		(duplicate_pad_numbers_are_jumpers no)
		(fp_line
			(start -4.533392 2.249932)
			(end 4.533392 2.249932)
			(stroke
				(width 0.1524)
				(type default)
			)
			(layer "B.SilkS")
		)
		(fp_line
			(start 4.533392 2.249932)
			(end 4.533392 -2.249932)
			(stroke
				(width 0.1524)
				(type default)
			)
			(layer "B.SilkS")
		)
		(fp_line
			(start -4.533392 -2.249932)
			(end -4.533392 2.249932)
			(stroke
				(width 0.1524)
				(type default)
			)
			(layer "B.SilkS")
		)
		(fp_line
			(start 4.533392 -2.249932)
			(end -4.533392 -2.249932)
			(stroke
				(width 0.1524)
				(type default)
			)
			(layer "B.SilkS")
		)
		(fp_poly
			(pts
				(xy 4.533392 -2.326132) (xy 5.39242 -2.326132) (xy 5.39242 2.326132) (xy 4.533392 2.326132)
			)
			(stroke
				(width 0)
				(type default)
			)
			(fill yes)
			(layer "B.SilkS")
		)
		(fp_line
			(start -3.750056 2.249932)
			(end 3.750056 2.249932)
			(stroke
				(width 0.1)
				(type default)
			)
			(layer "B.Fab")
		)
		(fp_line
			(start 3.750056 2.249932)
			(end 3.750056 -2.249932)
			(stroke
				(width 0.1)
				(type default)
			)
			(layer "B.Fab")
		)
		(fp_line
			(start -3.750056 -2.249932)
			(end -3.750056 2.249932)
			(stroke
				(width 0.1)
				(type default)
			)
			(layer "B.Fab")
		)
		(fp_line
			(start 3.750056 -2.249932)
			(end -3.750056 -2.249932)
			(stroke
				(width 0.1)
				(type default)
			)
			(layer "B.Fab")
		)
		(fp_text user "+"
			(at 6.322314 0.786384 180)
			(unlocked yes)
			(layer "B.SilkS")
			(effects
				(font
					(size 1.905 1.4224)
					(thickness 0.1524)
				)
				(justify left mirror)
			)
		)
		(fp_text user "-"
			(at -4.8514 -0.14605 270)
			(unlocked yes)
			(layer "B.SilkS")
			(effects
				(font
					(size 1.905 1.4224)
					(thickness 0.1524)
				)
				(justify left mirror)
			)
		)
		(fp_text user "+"
			(at 6.322314 0.786384 180)
			(unlocked yes)
			(layer "B.Fab")
			(effects
				(font
					(size 1.905 1.4224)
					(thickness 0.1524)
				)
				(justify left mirror)
			)
		)
		(fp_text user "-"
			(at -4.8514 -0.14605 270)
			(unlocked yes)
			(layer "B.Fab")
			(effects
				(font
					(size 1.905 1.4224)
					(thickness 0.1524)
				)
				(justify left mirror)
			)
		)
		(pad "1" smd rect
			(at 3.199892 0 90)
			(size 2.413 2.8194)
			(layers "B.Cu" "B.Mask" "B.Paste")
			(net "PVCCFA_EHV_FIVRA_CPU1")
		)
		(pad "2" smd rect
			(at -3.199892 0 90)
			(size 2.413 2.8194)
			(layers "B.Cu" "B.Mask" "B.Paste")
			(net "GND")
		)
	)
	(footprint ""
		(layer "B.Cu")
		(at 353.619308 -248.498106 -90)
		(property "Reference" "C357"
			(at 0 0 90)
			(layer "B.SilkS")
			(hide yes)
			(effects
				(font
					(size 1.27 1.27)
				)
				(justify mirror)
			)
		)
		(property "Value" ""
			(at 0 0 90)
			(layer "B.Fab")
			(effects
				(font
					(size 1.27 1.27)
				)
				(justify mirror)
			)
		)
		(duplicate_pad_numbers_are_jumpers no)
		(fp_line
			(start -1.524 0.762)
			(end 1.524 0.762)
			(stroke
				(width 0.1524)
				(type default)
			)
			(layer "B.SilkS")
		)
		(fp_line
			(start 1.524 0.762)
			(end 1.524 -0.762)
			(stroke
				(width 0.1524)
				(type default)
			)
			(layer "B.SilkS")
		)
		(fp_line
			(start -1.524 -0.762)
			(end -1.524 0.762)
			(stroke
				(width 0.1524)
				(type default)
			)
			(layer "B.SilkS")
		)
		(fp_line
			(start 1.524 -0.762)
			(end -1.524 -0.762)
			(stroke
				(width 0.1524)
				(type default)
			)
			(layer "B.SilkS")
		)
		(fp_line
			(start -1.1049 0.724916)
			(end -1.1049 -0.724916)
			(stroke
				(width 0.1)
				(type default)
			)
			(layer "B.Fab")
		)
		(fp_line
			(start 1.1049 0.724916)
			(end -1.1049 0.724916)
			(stroke
				(width 0.1)
				(type default)
			)
			(layer "B.Fab")
		)
		(fp_line
			(start -1.1049 -0.724916)
			(end 1.1049 -0.724916)
			(stroke
				(width 0.1)
				(type default)
			)
			(layer "B.Fab")
		)
		(fp_line
			(start 1.1049 -0.724916)
			(end 1.1049 0.724916)
			(stroke
				(width 0.1)
				(type default)
			)
			(layer "B.Fab")
		)
		(pad "1" smd rect
			(at 0.889 0 270)
			(size 1.016 1.27)
			(layers "B.Cu" "B.Mask" "B.Paste")
			(net "PVCCIN_CPU0")
		)
		(pad "2" smd rect
			(at -0.889 0 270)
			(size 1.016 1.27)
			(layers "B.Cu" "B.Mask" "B.Paste")
			(net "GND")
		)
	)
	(footprint ""
		(layer "B.Cu")
		(at 34.846514 -166.733474)
		(property "Reference" "PR1410"
			(at 0 0 0)
			(layer "B.SilkS")
			(hide yes)
			(effects
				(font
					(size 1.27 1.27)
				)
				(justify mirror)
			)
		)
		(property "Value" ""
			(at 0 0 0)
			(layer "B.Fab")
			(effects
				(font
					(size 1.27 1.27)
				)
				(justify mirror)
			)
		)
		(duplicate_pad_numbers_are_jumpers no)
		(fp_line
			(start -0.7874 -0.4064)
			(end -0.7874 0.4064)
			(stroke
				(width 0.1524)
				(type default)
			)
			(layer "B.SilkS")
		)
		(fp_line
			(start -0.7874 0.4064)
			(end 0.7874 0.4064)
			(stroke
				(width 0.1524)
				(type default)
			)
			(layer "B.SilkS")
		)
		(fp_line
			(start 0.7874 -0.4064)
			(end -0.7874 -0.4064)
			(stroke
				(width 0.1524)
				(type default)
			)
			(layer "B.SilkS")
		)
		(fp_line
			(start 0.7874 0.4064)
			(end 0.7874 -0.4064)
			(stroke
				(width 0.1524)
				(type default)
			)
			(layer "B.SilkS")
		)
		(fp_line
			(start -0.67945 -0.3048)
			(end -0.67945 0.3048)
			(stroke
				(width 0.1)
				(type default)
			)
			(layer "B.Fab")
		)
		(fp_line
			(start -0.67945 0.3048)
			(end -0.120396 0.3048)
			(stroke
				(width 0.1)
				(type default)
			)
			(layer "B.Fab")
		)
		(fp_line
			(start -0.12065 -0.3048)
			(end -0.67945 -0.3048)
			(stroke
				(width 0.1)
				(type default)
			)
			(layer "B.Fab")
		)
		(fp_line
			(start -0.12065 -0.2794)
			(end -0.12065 -0.3048)
			(stroke
				(width 0.1)
				(type default)
			)
			(layer "B.Fab")
		)
		(fp_line
			(start -0.120396 0.2794)
			(end 0.12065 0.2794)
			(stroke
				(width 0.1)
				(type default)
			)
			(layer "B.Fab")
		)
		(fp_line
			(start -0.120396 0.3048)
			(end -0.120396 0.2794)
			(stroke
				(width 0.1)
				(type default)
			)
			(layer "B.Fab")
		)
		(fp_line
			(start 0.12065 -0.305054)
			(end 0.12065 -0.2794)
			(stroke
				(width 0.1)
				(type default)
			)
			(layer "B.Fab")
		)
		(fp_line
			(start 0.12065 -0.2794)
			(end -0.12065 -0.2794)
			(stroke
				(width 0.1)
				(type default)
			)
			(layer "B.Fab")
		)
		(fp_line
			(start 0.12065 0.2794)
			(end 0.12065 0.3048)
			(stroke
				(width 0.1)
				(type default)
			)
			(layer "B.Fab")
		)
		(fp_line
			(start 0.12065 0.3048)
			(end 0.67945 0.3048)
			(stroke
				(width 0.1)
				(type default)
			)
			(layer "B.Fab")
		)
		(fp_line
			(start 0.67945 -0.305054)
			(end 0.12065 -0.305054)
			(stroke
				(width 0.1)
				(type default)
			)
			(layer "B.Fab")
		)
		(fp_line
			(start 0.67945 0.3048)
			(end 0.67945 -0.305054)
			(stroke
				(width 0.1)
				(type default)
			)
			(layer "B.Fab")
		)
		(pad "1" smd circle
			(at 0.40005 0 180)
			(size 0 0)
			(layers "B.Cu" "B.Mask" "B.Paste")
			(net "P12V_AUX_CPU1_DIMM_ISEN_N")
		)
		(pad "2" smd circle
			(at -0.40005 0 180)
			(size 0 0)
			(layers "B.Cu" "B.Mask" "B.Paste")
			(net "PVCCD_HV_CPU1_ISENSE_N")
		)
	)
	(footprint ""
		(layer "B.Cu")
		(at 436.971694 -119.952008)
		(property "Reference" "R361"
			(at 0 0 0)
			(layer "B.SilkS")
			(hide yes)
			(effects
				(font
					(size 1.27 1.27)
				)
				(justify mirror)
			)
		)
		(property "Value" ""
			(at 0 0 0)
			(layer "B.Fab")
			(effects
				(font
					(size 1.27 1.27)
				)
				(justify mirror)
			)
		)
		(duplicate_pad_numbers_are_jumpers no)
		(fp_line
			(start -0.7874 -0.4064)
			(end -0.7874 0.4064)
			(stroke
				(width 0.1524)
				(type default)
			)
			(layer "B.SilkS")
		)
		(fp_line
			(start -0.7874 0.4064)
			(end 0.7874 0.4064)
			(stroke
				(width 0.1524)
				(type default)
			)
			(layer "B.SilkS")
		)
		(fp_line
			(start 0.7874 -0.4064)
			(end -0.7874 -0.4064)
			(stroke
				(width 0.1524)
				(type default)
			)
			(layer "B.SilkS")
		)
		(fp_line
			(start 0.7874 0.4064)
			(end 0.7874 -0.4064)
			(stroke
				(width 0.1524)
				(type default)
			)
			(layer "B.SilkS")
		)
		(fp_line
			(start -0.67945 -0.3048)
			(end -0.67945 0.3048)
			(stroke
				(width 0.1)
				(type default)
			)
			(layer "B.Fab")
		)
		(fp_line
			(start -0.67945 0.3048)
			(end -0.120396 0.3048)
			(stroke
				(width 0.1)
				(type default)
			)
			(layer "B.Fab")
		)
		(fp_line
			(start -0.12065 -0.3048)
			(end -0.67945 -0.3048)
			(stroke
				(width 0.1)
				(type default)
			)
			(layer "B.Fab")
		)
		(fp_line
			(start -0.12065 -0.2794)
			(end -0.12065 -0.3048)
			(stroke
				(width 0.1)
				(type default)
			)
			(layer "B.Fab")
		)
		(fp_line
			(start -0.120396 0.2794)
			(end 0.12065 0.2794)
			(stroke
				(width 0.1)
				(type default)
			)
			(layer "B.Fab")
		)
		(fp_line
			(start -0.120396 0.3048)
			(end -0.120396 0.2794)
			(stroke
				(width 0.1)
				(type default)
			)
			(layer "B.Fab")
		)
		(fp_line
			(start 0.12065 -0.305054)
			(end 0.12065 -0.2794)
			(stroke
				(width 0.1)
				(type default)
			)
			(layer "B.Fab")
		)
		(fp_line
			(start 0.12065 -0.2794)
			(end -0.12065 -0.2794)
			(stroke
				(width 0.1)
				(type default)
			)
			(layer "B.Fab")
		)
		(fp_line
			(start 0.12065 0.2794)
			(end 0.12065 0.3048)
			(stroke
				(width 0.1)
				(type default)
			)
			(layer "B.Fab")
		)
		(fp_line
			(start 0.12065 0.3048)
			(end 0.67945 0.3048)
			(stroke
				(width 0.1)
				(type default)
			)
			(layer "B.Fab")
		)
		(fp_line
			(start 0.67945 -0.305054)
			(end 0.12065 -0.305054)
			(stroke
				(width 0.1)
				(type default)
			)
			(layer "B.Fab")
		)
		(fp_line
			(start 0.67945 0.3048)
			(end 0.67945 -0.305054)
			(stroke
				(width 0.1)
				(type default)
			)
			(layer "B.Fab")
		)
		(pad "1" smd circle
			(at 0.40005 0 180)
			(size 0 0)
			(layers "B.Cu" "B.Mask" "B.Paste")
			(net "P3V3_AUX")
		)
		(pad "2" smd circle
			(at -0.40005 0 180)
			(size 0 0)
			(layers "B.Cu" "B.Mask" "B.Paste")
			(net "PWRGD_PVCCD_HV_CPU0_R")
		)
	)
	(footprint ""
		(layer "B.Cu")
		(at 65.55994 -379.0696)
		(property "Reference" "ME9"
			(at 9.652 -9.540748 0)
			(unlocked yes)
			(layer "B.SilkS")
			(effects
				(font
					(size 0.7874 0.5842)
					(thickness 0.1524)
				)
				(justify left mirror)
			)
		)
		(property "Value" ""
			(at 0 0 0)
			(layer "B.Fab")
			(effects
				(font
					(size 1.27 1.27)
				)
				(justify mirror)
			)
		)
		(duplicate_pad_numbers_are_jumpers no)
		(zone
			(layer "B.Cu")
			(hatch none 0.5)
			(connect_pads
				(clearance 0)
			)
			(min_thickness 0.25)
			(keepout
				(tracks allowed)
				(vias allowed)
				(pads allowed)
				(copperpour allowed)
				(footprints not_allowed)
			)
			(placement
				(enabled no)
				(sheetname "")
			)
			(fill
				(thermal_gap 0.5)
				(thermal_bridge_width 0.5)
				(island_removal_mode 0)
			)
			(polygon
				(pts
					(arc
						(start 75.55992 -379.0696)
						(mid 55.55996 -379.0696)
						(end 75.55992 -379.0696)
					)
				)
			)
		)
	)
)
